G04 ================== begin FILE IDENTIFICATION RECORD ==================*
G04 Layout Name:  9054_F0T_PDB_BD_GPU_F_V04_1213_1550.brd*
G04 Film Name:    outline*
G04 File Format:  Gerber RS274X*
G04 File Origin:  Cadence Allegro 17.2-S081*
G04 Origin Date:  Wed Dec 28 10:19:03 2022*
G04 *
G04 Layer:  BOARD GEOMETRY/DESIGN_OUTLINE*
G04 Layer:  BOARD GEOMETRY/CUTOUT*
G04 Layer:  BOARD GEOMETRY/OUTLINE*
G04 *
G04 Offset:    (0.00 0.00)*
G04 Mirror:    No*
G04 Mode:      Positive*
G04 Rotation:  0*
G04 FullContactRelief:  No*
G04 UndefLineWidth:     6.00*
G04 ================== end FILE IDENTIFICATION RECORD ====================*
%FSLAX25Y25*MOIN*%
%IR0*IPPOS*OFA0.00000B0.00000*MIA0B0*SFA1.00000B1.00000*%
%ADD10C,.006*%
G75*
%LPD*%
G75*
G54D10*
G01X1874016Y85709D02*
Y499094D01*
G03X1854331Y518780I-19686J0D01*
G01X1751969D01*
G02X1732283Y538465I0J19686D01*
G01Y603543D01*
G03X1712598Y623228I-19685J0D01*
G01X1629921D01*
G02X1610236Y642913I0J19685D01*
G01Y656102D01*
G03X1590551Y675787I-19685J0D01*
G01X1437008D01*
G03X1417323Y656102I0J-19685D01*
G01Y635039D01*
G02X1405512Y623228I-11811J0D01*
G01X1403543D01*
G03X1383858Y603543I0J-19685D01*
G01Y435039D01*
G02X1354331Y405512I-29527J0D01*
G01X377953D01*
G02X348425Y435039I-1J29527D01*
G01Y603543D01*
G03X328740Y623228I-19685J0D01*
G01X326772D01*
G02X314961Y635039I0J11811D01*
G01Y656102D01*
G03X295276Y675787I-19685J0D01*
G01X141732D01*
G03X122047Y656102I0J-19685D01*
G01Y642913D01*
G02X102362Y623228I-19685J0D01*
G01X19685D01*
G03X0Y603543I0J-19685D01*
G01Y19685D01*
G03X19685Y0I19685J0D01*
G01X1712598D01*
G03X1732283Y19685I0J19685D01*
G01Y46339D01*
G02X1751969Y66024I19685J0D01*
G01X1854331D01*
G03X1874016Y85709I0J19685D01*
G01X41339Y17717D02*
Y23763D01*
G03X38916Y32156I-15749J0D01*
G02X55572I8328J5245D01*
G03X53150Y23763I13326J-8392D01*
G01Y17717D01*
G02X41339I-5905J0D01*
G01Y23763D02*
G03X38916Y32156I-15749J0D01*
G02X55572I8328J5245D01*
G03X53150Y23763I13326J-8392D01*
G01Y17717D01*
G02X41339I-5905J0D01*
G01Y23763D01*
G01Y330709D02*
Y336756D01*
G03X38916Y345148I-15747J-1D01*
G02X55572I8328J5245D01*
G03X53150Y336756I13324J-8391D01*
G01Y330709D01*
G02X41339I-5905J0D01*
G01Y336756D02*
G03X38916Y345148I-15747J-1D01*
G02X55572I8328J5245D01*
G03X53150Y336756I13324J-8391D01*
G01Y330709D01*
G02X41339I-5905J0D01*
G01Y336756D01*
G01X19685Y541339D02*
G02X44882I12598J0D01*
G02X19685I-12599J0D01*
G01D02*
G02X44882I12598J0D01*
G02X19685I-12599J0D01*
G01X51181Y236614D02*
G02X66929I7874J0D01*
G02X51181I-7874J0D01*
G01D02*
G02X66929I7874J0D01*
G02X51181I-7874J0D01*
G01Y411614D02*
G02X66929I7874J0D01*
G02X51181I-7874J0D01*
G01D02*
G02X66929I7874J0D01*
G02X51181I-7874J0D01*
G01X46457Y498031D02*
G02X71654I12598J0D01*
G02X46457I-12599J0D01*
G01D02*
G02X71654I12598J0D01*
G02X46457I-12599J0D01*
G01X203691Y639094D02*
G02X212057I4183J0D01*
G02X203691I-4183J0D01*
G01D02*
G02X212057I4183J0D01*
G02X203691I-4183J0D01*
G01X236142Y15512D02*
G02X245591I4724J0D01*
G02X236142I-4724J0D01*
G01D02*
G02X245591I4724J0D01*
G02X236142I-4724J0D01*
G01X273622Y53150D02*
Y59196D01*
G03X271199Y67589I-15749J0D01*
G02X287856I8329J5246D01*
G03X285433Y59196I13326J-8393D01*
G01Y53150D01*
G02X273622I-5905J0D01*
G01Y59196D02*
G03X271199Y67589I-15749J0D01*
G02X287856I8329J5246D01*
G03X285433Y59196I13326J-8393D01*
G01Y53150D01*
G02X273622I-5905J0D01*
G01Y59196D01*
G01X283268Y628465D02*
G02X291535I4134J0D01*
G02X283268I-4134J0D01*
G01D02*
G02X291535I4134J0D01*
G02X283268I-4134J0D01*
G01X259646Y659961D02*
G02X267913I4134J0D01*
G02X259646I-4134J0D01*
G01D02*
G02X267913I4134J0D01*
G02X259646I-4134J0D01*
G01X296142Y10197D02*
G02X305591I4725J0D01*
G02X296142I-4724J0D01*
G01D02*
G02X305591I4725J0D01*
G02X296142I-4724J0D01*
G01X320866Y561024D02*
G02X309055I-5905J0D01*
G01Y567070D01*
G03X306632Y575463I-15749J0D01*
G02X323289I8329J5246D01*
G03X320866Y567070I13326J-8393D01*
G01Y561024D01*
G01X309055D02*
Y567070D01*
G03X306632Y575463I-15749J0D01*
G02X323289I8329J5246D01*
G03X320866Y567070I13326J-8393D01*
G01Y561024D01*
G02X309055I-5905J0D01*
G01X387795Y344488D02*
Y350535D01*
G03X385373Y358928I-15748J1D01*
G02X402029I8328J5245D01*
G03X399606Y350535I13326J-8393D01*
G01Y344488D01*
G02X387795I-5905J0D01*
G01Y350535D02*
G03X385373Y358928I-15748J1D01*
G02X402029I8328J5245D01*
G03X399606Y350535I13326J-8393D01*
G01Y344488D01*
G02X387795I-5905J0D01*
G01Y350535D01*
G01X742126Y64961D02*
Y71007D01*
G03X739703Y79400I-15749J0D01*
G02X756360I8329J5246D01*
G03X753937Y71007I13326J-8393D01*
G01Y64961D01*
G02X742126I-5905J0D01*
G01Y71007D02*
G03X739703Y79400I-15749J0D01*
G02X756360I8329J5246D01*
G03X753937Y71007I13326J-8393D01*
G01Y64961D01*
G02X742126I-5905J0D01*
G01Y71007D01*
G01X753937Y344488D02*
G02X742126I-5905J0D01*
G01Y350535D01*
G03X739703Y358928I-15749J0D01*
G02X756360I8329J5246D01*
G03X753937Y350535I13326J-8393D01*
G01Y344488D01*
G01X742126D02*
Y350535D01*
G03X739703Y358928I-15749J0D01*
G02X756360I8329J5246D01*
G03X753937Y350535I13326J-8393D01*
G01Y344488D01*
G02X742126I-5905J0D01*
G01X813780Y88465D02*
G02X830394I8307J0D01*
G02X813780I-8307J0D01*
G01D02*
G02X830394I8307J0D01*
G02X813780I-8307J0D01*
G01Y313504D02*
G02X830394I8307J0D01*
G02X813780I-8307J0D01*
G01D02*
G02X830394I8307J0D01*
G02X813780I-8307J0D01*
G01X931890Y88465D02*
G02X948504I8307J0D01*
G02X931890I-8307J0D01*
G01D02*
G02X948504I8307J0D01*
G02X931890I-8307J0D01*
G01Y313504D02*
G02X948504I8307J0D01*
G02X931890I-8307J0D01*
G01D02*
G02X948504I8307J0D01*
G02X931890I-8307J0D01*
G01X978346Y64961D02*
Y71007D01*
G03X975924Y79400I-15748J1D01*
G02X992580I8328J5245D01*
G03X990157Y71007I13326J-8393D01*
G01Y64961D01*
G02X978346I-5906J0D01*
G01Y71007D02*
G03X975924Y79400I-15748J1D01*
G02X992580I8328J5245D01*
G03X990157Y71007I13326J-8393D01*
G01Y64961D01*
G02X978346I-5906J0D01*
G01Y71007D01*
G01Y344488D02*
Y350535D01*
G03X975924Y358928I-15748J1D01*
G02X992580I8328J5245D01*
G03X990157Y350535I13326J-8393D01*
G01Y344488D01*
G02X978346I-5906J0D01*
G01Y350535D02*
G03X975924Y358928I-15748J1D01*
G02X992580I8328J5245D01*
G03X990157Y350535I13326J-8393D01*
G01Y344488D01*
G02X978346I-5906J0D01*
G01Y350535D01*
G01X1344488Y344488D02*
G02X1332677I-5905J0D01*
G01Y350535D01*
G03X1330254Y358928I-15749J0D01*
G02X1346911I8329J5246D01*
G03X1344488Y350535I13326J-8393D01*
G01Y344488D01*
G01X1332677D02*
Y350535D01*
G03X1330254Y358928I-15749J0D01*
G02X1346911I8329J5246D01*
G03X1344488Y350535I13326J-8393D01*
G01Y344488D01*
G02X1332677I-5905J0D01*
G01X1426693Y15512D02*
G02X1436142I4724J0D01*
G02X1426693I-4725J0D01*
G01D02*
G02X1436142I4724J0D01*
G02X1426693I-4725J0D01*
G01X1423228Y561024D02*
G02X1411417I-5906J0D01*
G01Y567070D01*
G03X1408995Y575463I-15748J1D01*
G02X1425651I8328J5245D01*
G03X1423228Y567070I13326J-8393D01*
G01Y561024D01*
G01X1411417D02*
Y567070D01*
G03X1408995Y575463I-15748J1D01*
G02X1425651I8328J5245D01*
G03X1423228Y567070I13326J-8393D01*
G01Y561024D01*
G02X1411417I-5906J0D01*
G01X1446850Y53150D02*
Y59196D01*
G03X1444428Y67589I-15748J1D01*
G02X1461084I8328J5245D01*
G03X1458661Y59196I13326J-8393D01*
G01Y53150D01*
G02X1446850I-5905J0D01*
G01Y59196D02*
G03X1444428Y67589I-15748J1D01*
G02X1461084I8328J5245D01*
G03X1458661Y59196I13326J-8393D01*
G01Y53150D01*
G02X1446850I-5905J0D01*
G01Y59196D01*
G01X1464370Y628465D02*
G02X1472638I4134J0D01*
G02X1464370I-4134J0D01*
G01D02*
G02X1472638I4134J0D01*
G02X1464370I-4134J0D01*
G01X1440748Y659961D02*
G02X1449016I4134J0D01*
G02X1440748I-4134J0D01*
G01D02*
G02X1449016I4134J0D01*
G02X1440748I-4134J0D01*
G01X1486693Y10197D02*
G02X1496142I4725J0D01*
G02X1486693I-4725J0D01*
G01D02*
G02X1496142I4725J0D01*
G02X1486693I-4725J0D01*
G01X1520226Y639094D02*
G02X1528593I4183J0D01*
G02X1520226I-4184J0D01*
G01D02*
G02X1528593I4183J0D01*
G02X1520226I-4184J0D01*
G01X1679134Y17717D02*
Y23763D01*
G03X1676711Y32156I-15749J0D01*
G02X1693368I8329J5246D01*
G03X1690945Y23763I13326J-8393D01*
G01Y17717D01*
G02X1679134I-5905J0D01*
G01Y23763D02*
G03X1676711Y32156I-15749J0D01*
G02X1693368I8329J5246D01*
G03X1690945Y23763I13326J-8393D01*
G01Y17717D01*
G02X1679134I-5905J0D01*
G01Y23763D01*
G01X1665354Y236614D02*
G02X1681102I7874J0D01*
G02X1665354I-7874J0D01*
G01D02*
G02X1681102I7874J0D01*
G02X1665354I-7874J0D01*
G01X1679134Y330709D02*
Y336756D01*
G03X1676711Y345148I-15747J-1D01*
G02X1693368I8329J5246D01*
G03X1690945Y336756I13324J-8393D01*
G01Y330709D01*
G02X1679134I-5905J0D01*
G01Y336756D02*
G03X1676711Y345148I-15747J-1D01*
G02X1693368I8329J5246D01*
G03X1690945Y336756I13324J-8393D01*
G01Y330709D01*
G02X1679134I-5905J0D01*
G01Y336756D01*
G01X1665354Y411614D02*
G02X1681102I7874J0D01*
G02X1665354I-7874J0D01*
G01D02*
G02X1681102I7874J0D01*
G02X1665354I-7874J0D01*
G01X1660630Y498031D02*
G02X1685827I12599J0D01*
G02X1660630I-12599J0D01*
G01D02*
G02X1685827I12599J0D01*
G02X1660630I-12599J0D01*
G01X1687402Y541339D02*
G02X1712598I12598J0D01*
G02X1687402I-12598J0D01*
G01D02*
G02X1712598I12598J0D01*
G02X1687402I-12598J0D01*
G01X1805118Y96457D02*
G02X1793307I-5906J0D01*
G01Y102504D01*
G03X1790884Y110896I-15747J-1D01*
G02X1807541I8329J5246D01*
G03X1805118Y102504I13324J-8393D01*
G01Y96457D01*
G01X1793307D02*
Y102504D01*
G03X1790884Y110896I-15747J-1D01*
G02X1807541I8329J5246D01*
G03X1805118Y102504I13324J-8393D01*
G01Y96457D01*
G02X1793307I-5906J0D01*
G01X1805118Y478346D02*
G02X1793307I-5906J0D01*
G01Y484393D01*
G03X1790884Y492786I-15749J0D01*
G02X1807541I8329J5246D01*
G03X1805118Y484393I13326J-8393D01*
G01Y478346D01*
G01X1793307D02*
Y484393D01*
G03X1790884Y492786I-15749J0D01*
G02X1807541I8329J5246D01*
G03X1805118Y484393I13326J-8393D01*
G01Y478346D01*
G02X1793307I-5906J0D01*
G01X1839865Y94037D02*
G03X1836480Y95965I-3386J-2009D01*
G01X1833031D01*
G02X1830079Y98917I0J2952D01*
G01Y99508D01*
G02X1833031Y102461I2952J1D01*
G01X1836480D01*
G03X1839865Y104388I0J3937D01*
G02Y94037I8718J-5176D01*
G01D02*
G03X1836480Y95965I-3386J-2009D01*
G01X1833031D01*
G02X1830079Y98917I0J2952D01*
G01Y99508D01*
G02X1833031Y102461I2952J1D01*
G01X1836480D01*
G03X1839865Y104388I0J3937D01*
G02Y94037I8718J-5176D01*
G01Y476518D02*
G03X1836480Y478445I-3385J-2010D01*
G01X1833031D01*
G02X1830079Y481398I0J2953D01*
G01Y481988D01*
G02X1833031Y484941I2952J0D01*
G01X1836480D01*
G03X1839865Y486868I0J3937D01*
G02Y476518I8717J-5175D01*
G01D02*
G03X1836480Y478445I-3385J-2010D01*
G01X1833031D01*
G02X1830079Y481398I0J2953D01*
G01Y481988D01*
G02X1833031Y484941I2953J0D01*
G01X1836480D01*
G03X1839865Y486868I0J3937D01*
G02Y476518I8717J-5175D01*
M02*
